(kicad_pcb
	(version 20260206)
	(generator "pcbnew")
	(generator_version "10.0")
	(general
		(thickness 1.6)
		(legacy_teardrops no)
	)
	(paper "A4")
	(title_block
		(title "01162023_DA0F0TEBIF0_F0T_Expander_BD_F_brd_V02_OCP.brd")
		(comment 1 "Grand Teton / footprints 5541-5547 of 9728")
	)
	(layers
		(0 "F.Cu" signal "TOP")
		(4 "In1.Cu" signal "GND")
		(6 "In2.Cu" signal "VCC")
		(8 "In3.Cu" signal "VCC1")
		(10 "In4.Cu" signal "GND1")
		(12 "In5.Cu" signal "IN1")
		(14 "In6.Cu" signal "GND2")
		(16 "In7.Cu" signal "IN2")
		(18 "In8.Cu" signal "GND3")
		(20 "In9.Cu" signal "IN3")
		(22 "In10.Cu" signal "GND4")
		(24 "In11.Cu" signal "IN4")
		(26 "In12.Cu" signal "GND5")
		(28 "In13.Cu" signal "IN5")
		(30 "In14.Cu" signal "GND6")
		(32 "In15.Cu" signal "IN6")
		(34 "In16.Cu" signal "GND7")
		(2 "B.Cu" signal "BOTTOM")
		(9 "F.Adhes" user "F.Adhesive")
		(11 "B.Adhes" user "B.Adhesive")
		(13 "F.Paste" user "Package Geometry/Pastemask Top")
		(15 "B.Paste" user "Package Geometry/Pastemask Bottom")
		(5 "F.SilkS" user "Ref Des/Silkscreen Top")
		(7 "B.SilkS" user "Ref Des/Silkscreen Bottom")
		(1 "F.Mask" user "Board Geometry/Soldermask Top")
		(3 "B.Mask" user "Board Geometry/Soldermask Bottom")
		(17 "Dwgs.User" user "User.Drawings")
		(19 "Cmts.User" user "User.Comments")
		(21 "Eco1.User" user "User.Eco1")
		(23 "Eco2.User" user "User.Eco2")
		(25 "Edge.Cuts" user "Board Geometry/Outline")
		(27 "Margin" user)
		(31 "F.CrtYd" user "Package Geometry/Place Bound Top")
		(29 "B.CrtYd" user "Package Geometry/Place Bound Bottom")
		(35 "F.Fab" user "Ref Des/Assembly Top")
		(33 "B.Fab" user "Ref Des/Assembly Bottom")
	)
	(footprint ""
		(layer "F.Cu")
		(at 109.668056 -128.0541 90)
		(property "Reference" "PC301"
			(at 0 0 90)
			(layer "F.SilkS")
			(hide yes)
			(effects
				(font
					(size 1.27 1.27)
				)
			)
		)
		(property "Value" ""
			(at 0 0 90)
			(layer "F.Fab")
			(effects
				(font
					(size 1.27 1.27)
				)
			)
		)
		(duplicate_pad_numbers_are_jumpers no)
		(fp_line
			(start 1.524 -0.762)
			(end 1.524 0.762)
			(stroke
				(width 0.1524)
				(type default)
			)
			(layer "F.SilkS")
		)
		(fp_line
			(start -1.524 -0.762)
			(end 1.524 -0.762)
			(stroke
				(width 0.1524)
				(type default)
			)
			(layer "F.SilkS")
		)
		(fp_line
			(start 1.524 0.762)
			(end -1.524 0.762)
			(stroke
				(width 0.1524)
				(type default)
			)
			(layer "F.SilkS")
		)
		(fp_line
			(start -1.524 0.762)
			(end -1.524 -0.762)
			(stroke
				(width 0.1524)
				(type default)
			)
			(layer "F.SilkS")
		)
		(fp_line
			(start 1.1049 -0.724916)
			(end -1.1049 -0.724916)
			(stroke
				(width 0.1)
				(type default)
			)
			(layer "F.Fab")
		)
		(fp_line
			(start -1.1049 -0.724916)
			(end -1.1049 0.724916)
			(stroke
				(width 0.1)
				(type default)
			)
			(layer "F.Fab")
		)
		(fp_line
			(start 1.1049 0.724916)
			(end 1.1049 -0.724916)
			(stroke
				(width 0.1)
				(type default)
			)
			(layer "F.Fab")
		)
		(fp_line
			(start -1.1049 0.724916)
			(end 1.1049 0.724916)
			(stroke
				(width 0.1)
				(type default)
			)
			(layer "F.Fab")
		)
		(pad "1" smd rect
			(at -0.889 0 270)
			(size 1.016 1.27)
			(layers "F.Cu" "F.Mask" "F.Paste")
			(net "P3V3")
		)
		(pad "2" smd rect
			(at 0.889 0 270)
			(size 1.016 1.27)
			(layers "F.Cu" "F.Mask" "F.Paste")
			(net "GND")
		)
	)
	(footprint ""
		(layer "F.Cu")
		(at 123.71324 -140.392404 180)
		(property "Reference" "PC338"
			(at 0 0 180)
			(layer "F.SilkS")
			(hide yes)
			(effects
				(font
					(size 1.27 1.27)
				)
			)
		)
		(property "Value" ""
			(at 0 0 180)
			(layer "F.Fab")
			(effects
				(font
					(size 1.27 1.27)
				)
			)
		)
		(duplicate_pad_numbers_are_jumpers no)
		(fp_line
			(start 0.7874 0.4064)
			(end -0.7874 0.4064)
			(stroke
				(width 0.1524)
				(type default)
			)
			(layer "F.SilkS")
		)
		(fp_line
			(start 0.7874 -0.4064)
			(end 0.7874 0.4064)
			(stroke
				(width 0.1524)
				(type default)
			)
			(layer "F.SilkS")
		)
		(fp_line
			(start -0.7874 0.4064)
			(end -0.7874 -0.4064)
			(stroke
				(width 0.1524)
				(type default)
			)
			(layer "F.SilkS")
		)
		(fp_line
			(start -0.7874 -0.4064)
			(end 0.7874 -0.4064)
			(stroke
				(width 0.1524)
				(type default)
			)
			(layer "F.SilkS")
		)
		(fp_line
			(start 0.6858 0.3048)
			(end 0.1016 0.3048)
			(stroke
				(width 0.1)
				(type default)
			)
			(layer "F.Fab")
		)
		(fp_line
			(start 0.6858 -0.3048)
			(end 0.6858 0.3048)
			(stroke
				(width 0.1)
				(type default)
			)
			(layer "F.Fab")
		)
		(fp_line
			(start 0.1016 0.3048)
			(end 0.1016 0.2794)
			(stroke
				(width 0.1)
				(type default)
			)
			(layer "F.Fab")
		)
		(fp_line
			(start 0.1016 0.2794)
			(end -0.1016 0.2794)
			(stroke
				(width 0.1)
				(type default)
			)
			(layer "F.Fab")
		)
		(fp_line
			(start 0.1016 -0.2794)
			(end 0.1016 -0.3048)
			(stroke
				(width 0.1)
				(type default)
			)
			(layer "F.Fab")
		)
		(fp_line
			(start 0.1016 -0.3048)
			(end 0.6858 -0.3048)
			(stroke
				(width 0.1)
				(type default)
			)
			(layer "F.Fab")
		)
		(fp_line
			(start -0.1016 0.3048)
			(end -0.6858 0.3048)
			(stroke
				(width 0.1)
				(type default)
			)
			(layer "F.Fab")
		)
		(fp_line
			(start -0.1016 0.2794)
			(end -0.1016 0.3048)
			(stroke
				(width 0.1)
				(type default)
			)
			(layer "F.Fab")
		)
		(fp_line
			(start -0.1016 -0.2794)
			(end 0.1016 -0.2794)
			(stroke
				(width 0.1)
				(type default)
			)
			(layer "F.Fab")
		)
		(fp_line
			(start -0.1016 -0.3048)
			(end -0.1016 -0.2794)
			(stroke
				(width 0.1)
				(type default)
			)
			(layer "F.Fab")
		)
		(fp_line
			(start -0.6858 0.3048)
			(end -0.6858 -0.3048)
			(stroke
				(width 0.1)
				(type default)
			)
			(layer "F.Fab")
		)
		(fp_line
			(start -0.6858 -0.3048)
			(end -0.1016 -0.3048)
			(stroke
				(width 0.1)
				(type default)
			)
			(layer "F.Fab")
		)
		(pad "1" smd rect
			(at -0.40005 0)
			(size 0.4572 0.508)
			(layers "F.Cu" "F.Mask" "F.Paste")
			(net "P12V_NIC2_SS")
		)
		(pad "2" smd rect
			(at 0.40005 0)
			(size 0.4572 0.508)
			(layers "F.Cu" "F.Mask" "F.Paste")
			(net "GND")
		)
	)
	(footprint ""
		(layer "F.Cu")
		(at 4.526788 -53.697124 -90)
		(property "Reference" "PC510"
			(at 0 0 270)
			(layer "F.SilkS")
			(hide yes)
			(effects
				(font
					(size 1.27 1.27)
				)
			)
		)
		(property "Value" ""
			(at 0 0 270)
			(layer "F.Fab")
			(effects
				(font
					(size 1.27 1.27)
				)
			)
		)
		(duplicate_pad_numbers_are_jumpers no)
		(fp_line
			(start -0.7874 0.4064)
			(end -0.7874 -0.4064)
			(stroke
				(width 0.1524)
				(type default)
			)
			(layer "F.SilkS")
		)
		(fp_line
			(start 0.7874 0.4064)
			(end -0.7874 0.4064)
			(stroke
				(width 0.1524)
				(type default)
			)
			(layer "F.SilkS")
		)
		(fp_line
			(start -0.7874 -0.4064)
			(end 0.7874 -0.4064)
			(stroke
				(width 0.1524)
				(type default)
			)
			(layer "F.SilkS")
		)
		(fp_line
			(start 0.7874 -0.4064)
			(end 0.7874 0.4064)
			(stroke
				(width 0.1524)
				(type default)
			)
			(layer "F.SilkS")
		)
		(fp_line
			(start -0.67945 0.3048)
			(end -0.67945 -0.305054)
			(stroke
				(width 0.1)
				(type default)
			)
			(layer "F.Fab")
		)
		(fp_line
			(start -0.12065 0.3048)
			(end -0.67945 0.3048)
			(stroke
				(width 0.1)
				(type default)
			)
			(layer "F.Fab")
		)
		(fp_line
			(start 0.120396 0.3048)
			(end 0.120396 0.2794)
			(stroke
				(width 0.1)
				(type default)
			)
			(layer "F.Fab")
		)
		(fp_line
			(start 0.67945 0.3048)
			(end 0.120396 0.3048)
			(stroke
				(width 0.1)
				(type default)
			)
			(layer "F.Fab")
		)
		(fp_line
			(start -0.12065 0.2794)
			(end -0.12065 0.3048)
			(stroke
				(width 0.1)
				(type default)
			)
			(layer "F.Fab")
		)
		(fp_line
			(start 0.120396 0.2794)
			(end -0.12065 0.2794)
			(stroke
				(width 0.1)
				(type default)
			)
			(layer "F.Fab")
		)
		(fp_line
			(start -0.12065 -0.2794)
			(end 0.12065 -0.2794)
			(stroke
				(width 0.1)
				(type default)
			)
			(layer "F.Fab")
		)
		(fp_line
			(start 0.12065 -0.2794)
			(end 0.12065 -0.3048)
			(stroke
				(width 0.1)
				(type default)
			)
			(layer "F.Fab")
		)
		(fp_line
			(start 0.12065 -0.3048)
			(end 0.67945 -0.3048)
			(stroke
				(width 0.1)
				(type default)
			)
			(layer "F.Fab")
		)
		(fp_line
			(start 0.67945 -0.3048)
			(end 0.67945 0.3048)
			(stroke
				(width 0.1)
				(type default)
			)
			(layer "F.Fab")
		)
		(fp_line
			(start -0.67945 -0.305054)
			(end -0.12065 -0.305054)
			(stroke
				(width 0.1)
				(type default)
			)
			(layer "F.Fab")
		)
		(fp_line
			(start -0.12065 -0.305054)
			(end -0.12065 -0.2794)
			(stroke
				(width 0.1)
				(type default)
			)
			(layer "F.Fab")
		)
		(pad "1" smd circle
			(at -0.40005 0 270)
			(size 0 0)
			(layers "F.Cu" "F.Mask" "F.Paste")
			(net "P3V3_AUX")
		)
		(pad "2" smd circle
			(at 0.40005 0 270)
			(size 0 0)
			(layers "F.Cu" "F.Mask" "F.Paste")
			(net "GND")
		)
	)
	(footprint ""
		(layer "F.Cu")
		(at 323.917818 -218.309698 180)
		(property "Reference" "R2984"
			(at 0 0 180)
			(layer "F.SilkS")
			(hide yes)
			(effects
				(font
					(size 1.27 1.27)
				)
			)
		)
		(property "Value" ""
			(at 0 0 180)
			(layer "F.Fab")
			(effects
				(font
					(size 1.27 1.27)
				)
			)
		)
		(duplicate_pad_numbers_are_jumpers no)
		(fp_line
			(start 0.7874 0.4064)
			(end -0.7874 0.4064)
			(stroke
				(width 0.1524)
				(type default)
			)
			(layer "F.SilkS")
		)
		(fp_line
			(start 0.7874 -0.4064)
			(end 0.7874 0.4064)
			(stroke
				(width 0.1524)
				(type default)
			)
			(layer "F.SilkS")
		)
		(fp_line
			(start -0.7874 0.4064)
			(end -0.7874 -0.4064)
			(stroke
				(width 0.1524)
				(type default)
			)
			(layer "F.SilkS")
		)
		(fp_line
			(start -0.7874 -0.4064)
			(end 0.7874 -0.4064)
			(stroke
				(width 0.1524)
				(type default)
			)
			(layer "F.SilkS")
		)
		(fp_line
			(start 0.67945 0.3048)
			(end 0.120396 0.3048)
			(stroke
				(width 0.1)
				(type default)
			)
			(layer "F.Fab")
		)
		(fp_line
			(start 0.67945 -0.3048)
			(end 0.67945 0.3048)
			(stroke
				(width 0.1)
				(type default)
			)
			(layer "F.Fab")
		)
		(fp_line
			(start 0.12065 -0.2794)
			(end 0.12065 -0.3048)
			(stroke
				(width 0.1)
				(type default)
			)
			(layer "F.Fab")
		)
		(fp_line
			(start 0.12065 -0.3048)
			(end 0.67945 -0.3048)
			(stroke
				(width 0.1)
				(type default)
			)
			(layer "F.Fab")
		)
		(fp_line
			(start 0.120396 0.3048)
			(end 0.120396 0.2794)
			(stroke
				(width 0.1)
				(type default)
			)
			(layer "F.Fab")
		)
		(fp_line
			(start 0.120396 0.2794)
			(end -0.12065 0.2794)
			(stroke
				(width 0.1)
				(type default)
			)
			(layer "F.Fab")
		)
		(fp_line
			(start -0.12065 0.3048)
			(end -0.67945 0.3048)
			(stroke
				(width 0.1)
				(type default)
			)
			(layer "F.Fab")
		)
		(fp_line
			(start -0.12065 0.2794)
			(end -0.12065 0.3048)
			(stroke
				(width 0.1)
				(type default)
			)
			(layer "F.Fab")
		)
		(fp_line
			(start -0.12065 -0.2794)
			(end 0.12065 -0.2794)
			(stroke
				(width 0.1)
				(type default)
			)
			(layer "F.Fab")
		)
		(fp_line
			(start -0.12065 -0.305054)
			(end -0.12065 -0.2794)
			(stroke
				(width 0.1)
				(type default)
			)
			(layer "F.Fab")
		)
		(fp_line
			(start -0.67945 0.3048)
			(end -0.67945 -0.305054)
			(stroke
				(width 0.1)
				(type default)
			)
			(layer "F.Fab")
		)
		(fp_line
			(start -0.67945 -0.305054)
			(end -0.12065 -0.305054)
			(stroke
				(width 0.1)
				(type default)
			)
			(layer "F.Fab")
		)
		(pad "1" smd circle
			(at -0.40005 0 180)
			(size 0 0)
			(layers "F.Cu" "F.Mask" "F.Paste")
			(net "LED_POSTCODE_6")
		)
		(pad "2" smd circle
			(at 0.40005 0 180)
			(size 0 0)
			(layers "F.Cu" "F.Mask" "F.Paste")
			(net "LED_POSTCODE_R_6")
		)
	)
	(footprint ""
		(layer "F.Cu")
		(at 82.661506 -121.391172 180)
		(property "Reference" "C29"
			(at 0 0 180)
			(layer "F.SilkS")
			(hide yes)
			(effects
				(font
					(size 1.27 1.27)
				)
			)
		)
		(property "Value" ""
			(at 0 0 180)
			(layer "F.Fab")
			(effects
				(font
					(size 1.27 1.27)
				)
			)
		)
		(duplicate_pad_numbers_are_jumpers no)
		(fp_line
			(start 0.299974 0.150114)
			(end -0.299974 0.150114)
			(stroke
				(width 0.1)
				(type default)
			)
			(layer "F.Fab")
		)
		(fp_line
			(start 0.299974 -0.150114)
			(end 0.299974 0.150114)
			(stroke
				(width 0.1)
				(type default)
			)
			(layer "F.Fab")
		)
		(fp_line
			(start -0.299974 0.150114)
			(end -0.299974 -0.150114)
			(stroke
				(width 0.1)
				(type default)
			)
			(layer "F.Fab")
		)
		(fp_line
			(start -0.299974 -0.150114)
			(end 0.299974 -0.150114)
			(stroke
				(width 0.1)
				(type default)
			)
			(layer "F.Fab")
		)
		(pad "1" smd rect
			(at -0.2667 0 180)
			(size 0.3048 0.381)
			(layers "F.Cu" "F.Mask" "F.Paste")
			(net "P5E_PEX0_STN0_TX_DP<1>")
		)
		(pad "2" smd rect
			(at 0.2667 0 180)
			(size 0.3048 0.381)
			(layers "F.Cu" "F.Mask" "F.Paste")
			(net "P5E_PEX0_STN0_TX_C_DP<1>")
		)
	)
	(footprint ""
		(layer "F.Cu")
		(at 330.473812 -72.766682 90)
		(property "Reference" "PR7083"
			(at 0 0 90)
			(layer "F.SilkS")
			(hide yes)
			(effects
				(font
					(size 1.27 1.27)
				)
			)
		)
		(property "Value" ""
			(at 0 0 90)
			(layer "F.Fab")
			(effects
				(font
					(size 1.27 1.27)
				)
			)
		)
		(duplicate_pad_numbers_are_jumpers no)
		(fp_line
			(start 0.7874 -0.4064)
			(end 0.7874 0.4064)
			(stroke
				(width 0.1524)
				(type default)
			)
			(layer "F.SilkS")
		)
		(fp_line
			(start -0.7874 -0.4064)
			(end 0.7874 -0.4064)
			(stroke
				(width 0.1524)
				(type default)
			)
			(layer "F.SilkS")
		)
		(fp_line
			(start 0.7874 0.4064)
			(end -0.7874 0.4064)
			(stroke
				(width 0.1524)
				(type default)
			)
			(layer "F.SilkS")
		)
		(fp_line
			(start -0.7874 0.4064)
			(end -0.7874 -0.4064)
			(stroke
				(width 0.1524)
				(type default)
			)
			(layer "F.SilkS")
		)
		(fp_line
			(start -0.12065 -0.305054)
			(end -0.12065 -0.2794)
			(stroke
				(width 0.1)
				(type default)
			)
			(layer "F.Fab")
		)
		(fp_line
			(start -0.67945 -0.305054)
			(end -0.12065 -0.305054)
			(stroke
				(width 0.1)
				(type default)
			)
			(layer "F.Fab")
		)
		(fp_line
			(start 0.67945 -0.3048)
			(end 0.67945 0.3048)
			(stroke
				(width 0.1)
				(type default)
			)
			(layer "F.Fab")
		)
		(fp_line
			(start 0.12065 -0.3048)
			(end 0.67945 -0.3048)
			(stroke
				(width 0.1)
				(type default)
			)
			(layer "F.Fab")
		)
		(fp_line
			(start 0.12065 -0.2794)
			(end 0.12065 -0.3048)
			(stroke
				(width 0.1)
				(type default)
			)
			(layer "F.Fab")
		)
		(fp_line
			(start -0.12065 -0.2794)
			(end 0.12065 -0.2794)
			(stroke
				(width 0.1)
				(type default)
			)
			(layer "F.Fab")
		)
		(fp_line
			(start 0.120396 0.2794)
			(end -0.12065 0.2794)
			(stroke
				(width 0.1)
				(type default)
			)
			(layer "F.Fab")
		)
		(fp_line
			(start -0.12065 0.2794)
			(end -0.12065 0.3048)
			(stroke
				(width 0.1)
				(type default)
			)
			(layer "F.Fab")
		)
		(fp_line
			(start 0.67945 0.3048)
			(end 0.120396 0.3048)
			(stroke
				(width 0.1)
				(type default)
			)
			(layer "F.Fab")
		)
		(fp_line
			(start 0.120396 0.3048)
			(end 0.120396 0.2794)
			(stroke
				(width 0.1)
				(type default)
			)
			(layer "F.Fab")
		)
		(fp_line
			(start -0.12065 0.3048)
			(end -0.67945 0.3048)
			(stroke
				(width 0.1)
				(type default)
			)
			(layer "F.Fab")
		)
		(fp_line
			(start -0.67945 0.3048)
			(end -0.67945 -0.305054)
			(stroke
				(width 0.1)
				(type default)
			)
			(layer "F.Fab")
		)
		(pad "1" smd circle
			(at -0.40005 0 90)
			(size 0 0)
			(layers "F.Cu" "F.Mask" "F.Paste")
			(net "P12V_SSD11_CO_MODE")
		)
		(pad "2" smd circle
			(at 0.40005 0 90)
			(size 0 0)
			(layers "F.Cu" "F.Mask" "F.Paste")
			(net "GND")
		)
	)
	(footprint ""
		(layer "F.Cu")
		(at 188.806074 -414.583626 90)
		(property "Reference" "R6779"
			(at 0 0 90)
			(layer "F.SilkS")
			(hide yes)
			(effects
				(font
					(size 1.27 1.27)
				)
			)
		)
		(property "Value" ""
			(at 0 0 90)
			(layer "F.Fab")
			(effects
				(font
					(size 1.27 1.27)
				)
			)
		)
		(duplicate_pad_numbers_are_jumpers no)
		(fp_line
			(start 0.7874 -0.4064)
			(end 0.7874 0.4064)
			(stroke
				(width 0.1524)
				(type default)
			)
			(layer "F.SilkS")
		)
		(fp_line
			(start -0.7874 -0.4064)
			(end 0.7874 -0.4064)
			(stroke
				(width 0.1524)
				(type default)
			)
			(layer "F.SilkS")
		)
		(fp_line
			(start 0.7874 0.4064)
			(end -0.7874 0.4064)
			(stroke
				(width 0.1524)
				(type default)
			)
			(layer "F.SilkS")
		)
		(fp_line
			(start -0.7874 0.4064)
			(end -0.7874 -0.4064)
			(stroke
				(width 0.1524)
				(type default)
			)
			(layer "F.SilkS")
		)
		(fp_line
			(start -0.12065 -0.305054)
			(end -0.12065 -0.2794)
			(stroke
				(width 0.1)
				(type default)
			)
			(layer "F.Fab")
		)
		(fp_line
			(start -0.67945 -0.305054)
			(end -0.12065 -0.305054)
			(stroke
				(width 0.1)
				(type default)
			)
			(layer "F.Fab")
		)
		(fp_line
			(start 0.67945 -0.3048)
			(end 0.67945 0.3048)
			(stroke
				(width 0.1)
				(type default)
			)
			(layer "F.Fab")
		)
		(fp_line
			(start 0.12065 -0.3048)
			(end 0.67945 -0.3048)
			(stroke
				(width 0.1)
				(type default)
			)
			(layer "F.Fab")
		)
		(fp_line
			(start 0.12065 -0.2794)
			(end 0.12065 -0.3048)
			(stroke
				(width 0.1)
				(type default)
			)
			(layer "F.Fab")
		)
		(fp_line
			(start -0.12065 -0.2794)
			(end 0.12065 -0.2794)
			(stroke
				(width 0.1)
				(type default)
			)
			(layer "F.Fab")
		)
		(fp_line
			(start 0.120396 0.2794)
			(end -0.12065 0.2794)
			(stroke
				(width 0.1)
				(type default)
			)
			(layer "F.Fab")
		)
		(fp_line
			(start -0.12065 0.2794)
			(end -0.12065 0.3048)
			(stroke
				(width 0.1)
				(type default)
			)
			(layer "F.Fab")
		)
		(fp_line
			(start 0.67945 0.3048)
			(end 0.120396 0.3048)
			(stroke
				(width 0.1)
				(type default)
			)
			(layer "F.Fab")
		)
		(fp_line
			(start 0.120396 0.3048)
			(end 0.120396 0.2794)
			(stroke
				(width 0.1)
				(type default)
			)
			(layer "F.Fab")
		)
		(fp_line
			(start -0.12065 0.3048)
			(end -0.67945 0.3048)
			(stroke
				(width 0.1)
				(type default)
			)
			(layer "F.Fab")
		)
		(fp_line
			(start -0.67945 0.3048)
			(end -0.67945 -0.305054)
			(stroke
				(width 0.1)
				(type default)
			)
			(layer "F.Fab")
		)
		(pad "1" smd circle
			(at -0.40005 0 90)
			(size 0 0)
			(layers "F.Cu" "F.Mask" "F.Paste")
			(net "P12V_AUX")
		)
		(pad "2" smd circle
			(at 0.40005 0 90)
			(size 0 0)
			(layers "F.Cu" "F.Mask" "F.Paste")
			(net "P12V_AUX_FP_TRIGGER")
		)
	)
)
